# T6G (Grand Teton) — schematic netlist excerpt (pin names and nets, part order shuffled) for the footprints in the layout excerpt that follows; sources: Cadence DE-HDL packaged netlist, KiCad conversion of 04192023_DAF0TMB3IC0_F0TG_MB_C_brd_V02_OCP.brd

R773  Q_RES  84.5K 1% CHIP  pkg 0402LF  page 103 : A = PD_CHF_CPU1_DIMM_SAA ; B = GND
R548  Q_RES  4.7K 5% EMPTY  pkg 0402LF  page 55 : A = CPU1_SLP_S5_N ; B = PVDD18_S5_P1
C650  Q_CAP  0.1UF 10V 10% X7S  pkg C0201  page 290 : A = P0V9_CPU0_RT1_2A ; B = GND

(kicad_pcb
	(version 20260206)
	(generator "pcbnew")
	(generator_version "10.0")
	(general
		(thickness 1.6)
		(legacy_teardrops no)
	)
	(paper "A4")
	(title_block
		(title "04192023_DAF0TMB3IC0_F0TG_MB_C_brd_V02_OCP.brd")
		(comment 1 "Grand Teton / footprints 6860-6862 of 8354")
	)
	(layers
		(0 "F.Cu" signal "TOP")
		(4 "In1.Cu" signal "GND")
		(6 "In2.Cu" signal "IN1")
		(8 "In3.Cu" signal "GND1")
		(10 "In4.Cu" signal "IN2")
		(12 "In5.Cu" signal "GND2")
		(14 "In6.Cu" signal "IN3")
		(16 "In7.Cu" signal "GND3")
		(18 "In8.Cu" signal "VCC")
		(20 "In9.Cu" signal "VCC1")
		(22 "In10.Cu" signal "GND4")
		(24 "In11.Cu" signal "IN4")
		(26 "In12.Cu" signal "GND5")
		(28 "In13.Cu" signal "IN5")
		(30 "In14.Cu" signal "GND6")
		(32 "In15.Cu" signal "IN6")
		(34 "In16.Cu" signal "GND7")
		(2 "B.Cu" signal "BOTTOM")
		(9 "F.Adhes" user "F.Adhesive")
		(11 "B.Adhes" user "B.Adhesive")
		(13 "F.Paste" user "Package Geometry/Pastemask Top")
		(15 "B.Paste" user "Package Geometry/Pastemask Bottom")
		(5 "F.SilkS" user "Ref Des/Silkscreen Top")
		(7 "B.SilkS" user "Ref Des/Silkscreen Bottom")
		(1 "F.Mask" user "Board Geometry/Soldermask Top")
		(3 "B.Mask" user "Board Geometry/Soldermask Bottom")
		(17 "Dwgs.User" user "User.Drawings")
		(19 "Cmts.User" user "User.Comments")
		(21 "Eco1.User" user "User.Eco1")
		(23 "Eco2.User" user "User.Eco2")
		(25 "Edge.Cuts" user "Board Geometry/Outline")
		(27 "Margin" user)
		(31 "F.CrtYd" user "Package Geometry/Place Bound Top")
		(29 "B.CrtYd" user "Package Geometry/Place Bound Bottom")
		(35 "F.Fab" user "Ref Des/Assembly Top")
		(33 "B.Fab" user "Ref Des/Assembly Bottom")
	)
	(footprint ""
		(layer "B.Cu")
		(at 16.550386 -196.952616 -90)
		(property "Reference" "R773"
			(at 0 0 90)
			(layer "B.SilkS")
			(hide yes)
			(effects
				(font
					(size 1.27 1.27)
				)
				(justify mirror)
			)
		)
		(property "Value" ""
			(at 0 0 90)
			(layer "B.Fab")
			(effects
				(font
					(size 1.27 1.27)
				)
				(justify mirror)
			)
		)
		(duplicate_pad_numbers_are_jumpers no)
		(fp_line
			(start -0.7874 0.4064)
			(end 0.7874 0.4064)
			(stroke
				(width 0.1524)
				(type default)
			)
			(layer "B.SilkS")
		)
		(fp_line
			(start 0.7874 0.4064)
			(end 0.7874 -0.4064)
			(stroke
				(width 0.1524)
				(type default)
			)
			(layer "B.SilkS")
		)
		(fp_line
			(start -0.7874 -0.4064)
			(end -0.7874 0.4064)
			(stroke
				(width 0.1524)
				(type default)
			)
			(layer "B.SilkS")
		)
		(fp_line
			(start 0.7874 -0.4064)
			(end -0.7874 -0.4064)
			(stroke
				(width 0.1524)
				(type default)
			)
			(layer "B.SilkS")
		)
		(fp_line
			(start -0.67945 0.3048)
			(end -0.120396 0.3048)
			(stroke
				(width 0.1)
				(type default)
			)
			(layer "B.Fab")
		)
		(fp_line
			(start -0.120396 0.3048)
			(end -0.120396 0.2794)
			(stroke
				(width 0.1)
				(type default)
			)
			(layer "B.Fab")
		)
		(fp_line
			(start 0.12065 0.3048)
			(end 0.67945 0.3048)
			(stroke
				(width 0.1)
				(type default)
			)
			(layer "B.Fab")
		)
		(fp_line
			(start 0.67945 0.3048)
			(end 0.67945 -0.305054)
			(stroke
				(width 0.1)
				(type default)
			)
			(layer "B.Fab")
		)
		(fp_line
			(start -0.120396 0.2794)
			(end 0.12065 0.2794)
			(stroke
				(width 0.1)
				(type default)
			)
			(layer "B.Fab")
		)
		(fp_line
			(start 0.12065 0.2794)
			(end 0.12065 0.3048)
			(stroke
				(width 0.1)
				(type default)
			)
			(layer "B.Fab")
		)
		(fp_line
			(start -0.12065 -0.2794)
			(end -0.12065 -0.3048)
			(stroke
				(width 0.1)
				(type default)
			)
			(layer "B.Fab")
		)
		(fp_line
			(start 0.12065 -0.2794)
			(end -0.12065 -0.2794)
			(stroke
				(width 0.1)
				(type default)
			)
			(layer "B.Fab")
		)
		(fp_line
			(start -0.67945 -0.3048)
			(end -0.67945 0.3048)
			(stroke
				(width 0.1)
				(type default)
			)
			(layer "B.Fab")
		)
		(fp_line
			(start -0.12065 -0.3048)
			(end -0.67945 -0.3048)
			(stroke
				(width 0.1)
				(type default)
			)
			(layer "B.Fab")
		)
		(fp_line
			(start 0.12065 -0.305054)
			(end 0.12065 -0.2794)
			(stroke
				(width 0.1)
				(type default)
			)
			(layer "B.Fab")
		)
		(fp_line
			(start 0.67945 -0.305054)
			(end 0.12065 -0.305054)
			(stroke
				(width 0.1)
				(type default)
			)
			(layer "B.Fab")
		)
		(pad "1" smd circle
			(at 0.40005 0 90)
			(size 0 0)
			(layers "B.Cu" "B.Mask" "B.Paste")
			(net "PD_CHF_CPU1_DIMM_SAA")
		)
		(pad "2" smd circle
			(at -0.40005 0 90)
			(size 0 0)
			(layers "B.Cu" "B.Mask" "B.Paste")
			(net "GND")
		)
	)
	(footprint ""
		(layer "B.Cu")
		(at 156.151834 -321.814952 180)
		(property "Reference" "R548"
			(at 0 0 0)
			(layer "B.SilkS")
			(hide yes)
			(effects
				(font
					(size 1.27 1.27)
				)
				(justify mirror)
			)
		)
		(property "Value" ""
			(at 0 0 0)
			(layer "B.Fab")
			(effects
				(font
					(size 1.27 1.27)
				)
				(justify mirror)
			)
		)
		(duplicate_pad_numbers_are_jumpers no)
		(fp_line
			(start 0.7874 0.4064)
			(end 0.7874 -0.4064)
			(stroke
				(width 0.1524)
				(type default)
			)
			(layer "B.SilkS")
		)
		(fp_line
			(start 0.7874 -0.4064)
			(end -0.7874 -0.4064)
			(stroke
				(width 0.1524)
				(type default)
			)
			(layer "B.SilkS")
		)
		(fp_line
			(start -0.7874 0.4064)
			(end 0.7874 0.4064)
			(stroke
				(width 0.1524)
				(type default)
			)
			(layer "B.SilkS")
		)
		(fp_line
			(start -0.7874 -0.4064)
			(end -0.7874 0.4064)
			(stroke
				(width 0.1524)
				(type default)
			)
			(layer "B.SilkS")
		)
		(fp_line
			(start 0.67945 0.3048)
			(end 0.67945 -0.305054)
			(stroke
				(width 0.1)
				(type default)
			)
			(layer "B.Fab")
		)
		(fp_line
			(start 0.67945 -0.305054)
			(end 0.12065 -0.305054)
			(stroke
				(width 0.1)
				(type default)
			)
			(layer "B.Fab")
		)
		(fp_line
			(start 0.12065 0.3048)
			(end 0.67945 0.3048)
			(stroke
				(width 0.1)
				(type default)
			)
			(layer "B.Fab")
		)
		(fp_line
			(start 0.12065 0.2794)
			(end 0.12065 0.3048)
			(stroke
				(width 0.1)
				(type default)
			)
			(layer "B.Fab")
		)
		(fp_line
			(start 0.12065 -0.2794)
			(end -0.12065 -0.2794)
			(stroke
				(width 0.1)
				(type default)
			)
			(layer "B.Fab")
		)
		(fp_line
			(start 0.12065 -0.305054)
			(end 0.12065 -0.2794)
			(stroke
				(width 0.1)
				(type default)
			)
			(layer "B.Fab")
		)
		(fp_line
			(start -0.120396 0.3048)
			(end -0.120396 0.2794)
			(stroke
				(width 0.1)
				(type default)
			)
			(layer "B.Fab")
		)
		(fp_line
			(start -0.120396 0.2794)
			(end 0.12065 0.2794)
			(stroke
				(width 0.1)
				(type default)
			)
			(layer "B.Fab")
		)
		(fp_line
			(start -0.12065 -0.2794)
			(end -0.12065 -0.3048)
			(stroke
				(width 0.1)
				(type default)
			)
			(layer "B.Fab")
		)
		(fp_line
			(start -0.12065 -0.3048)
			(end -0.67945 -0.3048)
			(stroke
				(width 0.1)
				(type default)
			)
			(layer "B.Fab")
		)
		(fp_line
			(start -0.67945 0.3048)
			(end -0.120396 0.3048)
			(stroke
				(width 0.1)
				(type default)
			)
			(layer "B.Fab")
		)
		(fp_line
			(start -0.67945 -0.3048)
			(end -0.67945 0.3048)
			(stroke
				(width 0.1)
				(type default)
			)
			(layer "B.Fab")
		)
		(pad "1" smd circle
			(at 0.40005 0)
			(size 0 0)
			(layers "B.Cu" "B.Mask" "B.Paste")
			(net "CPU1_SLP_S5_N")
		)
		(pad "2" smd circle
			(at -0.40005 0)
			(size 0 0)
			(layers "B.Cu" "B.Mask" "B.Paste")
			(net "PVDD18_S5_P1")
		)
	)
	(footprint ""
		(layer "B.Cu")
		(at 337.24596 -396.393162 -90)
		(property "Reference" "C650"
			(at 0 0 90)
			(layer "B.SilkS")
			(hide yes)
			(effects
				(font
					(size 1.27 1.27)
				)
				(justify mirror)
			)
		)
		(property "Value" ""
			(at 0 0 90)
			(layer "B.Fab")
			(effects
				(font
					(size 1.27 1.27)
				)
				(justify mirror)
			)
		)
		(duplicate_pad_numbers_are_jumpers no)
		(fp_line
			(start -0.299974 0.150114)
			(end 0.299974 0.150114)
			(stroke
				(width 0.1)
				(type default)
			)
			(layer "B.Fab")
		)
		(fp_line
			(start 0.299974 0.150114)
			(end 0.299974 -0.150114)
			(stroke
				(width 0.1)
				(type default)
			)
			(layer "B.Fab")
		)
		(fp_line
			(start -0.299974 -0.150114)
			(end -0.299974 0.150114)
			(stroke
				(width 0.1)
				(type default)
			)
			(layer "B.Fab")
		)
		(fp_line
			(start 0.299974 -0.150114)
			(end -0.299974 -0.150114)
			(stroke
				(width 0.1)
				(type default)
			)
			(layer "B.Fab")
		)
		(pad "1" smd rect
			(at 0.2667 0 90)
			(size 0.3048 0.381)
			(layers "B.Cu" "B.Mask" "B.Paste")
			(net "P0V9_CPU0_RT1_2A")
		)
		(pad "2" smd rect
			(at -0.2667 0 90)
			(size 0.3048 0.381)
			(layers "B.Cu" "B.Mask" "B.Paste")
			(net "GND")
		)
	)
)
